(kicad_pcb
	(version 20260206)
	(generator "pcbnew")
	(generator_version "10.0")
	(general
		(thickness 1.6)
		(legacy_teardrops no)
	)
	(paper "A4")
	(title_block
		(title "9054_F0T_PDB_BD_GPU_F_V04_1213_1550_OCP.brd")
		(comment 1 "Grand Teton / footprints 100-103 of 608")
	)
	(layers
		(0 "F.Cu" signal "TOP")
		(4 "In1.Cu" signal "GND")
		(6 "In2.Cu" signal "IN1")
		(8 "In3.Cu" signal "GND1")
		(10 "In4.Cu" signal "VCC")
		(12 "In5.Cu" signal "VCC1")
		(14 "In6.Cu" signal "GND2")
		(16 "In7.Cu" signal "IN2")
		(18 "In8.Cu" signal "GND3")
		(2 "B.Cu" signal "BOTTOM")
		(9 "F.Adhes" user "F.Adhesive")
		(11 "B.Adhes" user "B.Adhesive")
		(13 "F.Paste" user "Package Geometry/Pastemask Top")
		(15 "B.Paste" user "Package Geometry/Pastemask Bottom")
		(5 "F.SilkS" user "Ref Des/Silkscreen Top")
		(7 "B.SilkS" user "Ref Des/Silkscreen Bottom")
		(1 "F.Mask" user "Board Geometry/Soldermask Top")
		(3 "B.Mask" user "Board Geometry/Soldermask Bottom")
		(17 "Dwgs.User" user "User.Drawings")
		(19 "Cmts.User" user "User.Comments")
		(21 "Eco1.User" user "User.Eco1")
		(23 "Eco2.User" user "User.Eco2")
		(25 "Edge.Cuts" user "Board Geometry/Outline")
		(27 "Margin" user)
		(31 "F.CrtYd" user "Package Geometry/Place Bound Top")
		(29 "B.CrtYd" user "Package Geometry/Place Bound Bottom")
		(35 "F.Fab" user "Ref Des/Assembly Top")
		(33 "B.Fab" user "Ref Des/Assembly Bottom")
	)
	(footprint ""
		(layer "F.Cu")
		(at 130.412236 -81.788 180)
		(property "Reference" "PR6994"
			(at 0 0 180)
			(layer "F.SilkS")
			(hide yes)
			(effects
				(font
					(size 1.27 1.27)
				)
			)
		)
		(property "Value" ""
			(at 0 0 180)
			(layer "F.Fab")
			(effects
				(font
					(size 1.27 1.27)
				)
			)
		)
		(duplicate_pad_numbers_are_jumpers no)
		(fp_line
			(start 0.7874 0.4064)
			(end -0.7874 0.4064)
			(stroke
				(width 0.1524)
				(type default)
			)
			(layer "F.SilkS")
		)
		(fp_line
			(start 0.7874 -0.4064)
			(end 0.7874 0.4064)
			(stroke
				(width 0.1524)
				(type default)
			)
			(layer "F.SilkS")
		)
		(fp_line
			(start -0.7874 0.4064)
			(end -0.7874 -0.4064)
			(stroke
				(width 0.1524)
				(type default)
			)
			(layer "F.SilkS")
		)
		(fp_line
			(start -0.7874 -0.4064)
			(end 0.7874 -0.4064)
			(stroke
				(width 0.1524)
				(type default)
			)
			(layer "F.SilkS")
		)
		(fp_line
			(start 0.67945 0.3048)
			(end 0.120396 0.3048)
			(stroke
				(width 0.1)
				(type default)
			)
			(layer "F.Fab")
		)
		(fp_line
			(start 0.67945 -0.3048)
			(end 0.67945 0.3048)
			(stroke
				(width 0.1)
				(type default)
			)
			(layer "F.Fab")
		)
		(fp_line
			(start 0.12065 -0.2794)
			(end 0.12065 -0.3048)
			(stroke
				(width 0.1)
				(type default)
			)
			(layer "F.Fab")
		)
		(fp_line
			(start 0.12065 -0.3048)
			(end 0.67945 -0.3048)
			(stroke
				(width 0.1)
				(type default)
			)
			(layer "F.Fab")
		)
		(fp_line
			(start 0.120396 0.3048)
			(end 0.120396 0.2794)
			(stroke
				(width 0.1)
				(type default)
			)
			(layer "F.Fab")
		)
		(fp_line
			(start 0.120396 0.2794)
			(end -0.12065 0.2794)
			(stroke
				(width 0.1)
				(type default)
			)
			(layer "F.Fab")
		)
		(fp_line
			(start -0.12065 0.3048)
			(end -0.67945 0.3048)
			(stroke
				(width 0.1)
				(type default)
			)
			(layer "F.Fab")
		)
		(fp_line
			(start -0.12065 0.2794)
			(end -0.12065 0.3048)
			(stroke
				(width 0.1)
				(type default)
			)
			(layer "F.Fab")
		)
		(fp_line
			(start -0.12065 -0.2794)
			(end 0.12065 -0.2794)
			(stroke
				(width 0.1)
				(type default)
			)
			(layer "F.Fab")
		)
		(fp_line
			(start -0.12065 -0.305054)
			(end -0.12065 -0.2794)
			(stroke
				(width 0.1)
				(type default)
			)
			(layer "F.Fab")
		)
		(fp_line
			(start -0.67945 0.3048)
			(end -0.67945 -0.305054)
			(stroke
				(width 0.1)
				(type default)
			)
			(layer "F.Fab")
		)
		(fp_line
			(start -0.67945 -0.305054)
			(end -0.12065 -0.305054)
			(stroke
				(width 0.1)
				(type default)
			)
			(layer "F.Fab")
		)
		(pad "1" smd rect
			(at -0.40005 0)
			(size 0.4572 0.508)
			(layers "F.Cu" "F.Mask" "F.Paste")
			(net "P52V_HS2_TEMP")
		)
		(pad "2" smd rect
			(at 0.40005 0)
			(size 0.4572 0.508)
			(layers "F.Cu" "F.Mask" "F.Paste")
			(net "P52V_HS2_TEMP_R")
		)
	)
	(footprint ""
		(layer "F.Cu")
		(at 414.46958 -32.75076 90)
		(property "Reference" "C100"
			(at 0 0 90)
			(layer "F.SilkS")
			(hide yes)
			(effects
				(font
					(size 1.27 1.27)
				)
			)
		)
		(property "Value" ""
			(at 0 0 90)
			(layer "F.Fab")
			(effects
				(font
					(size 1.27 1.27)
				)
			)
		)
		(duplicate_pad_numbers_are_jumpers no)
		(fp_line
			(start 0.7874 -0.4064)
			(end 0.7874 0.4064)
			(stroke
				(width 0.1524)
				(type default)
			)
			(layer "F.SilkS")
		)
		(fp_line
			(start -0.7874 -0.4064)
			(end 0.7874 -0.4064)
			(stroke
				(width 0.1524)
				(type default)
			)
			(layer "F.SilkS")
		)
		(fp_line
			(start 0.7874 0.4064)
			(end -0.7874 0.4064)
			(stroke
				(width 0.1524)
				(type default)
			)
			(layer "F.SilkS")
		)
		(fp_line
			(start -0.7874 0.4064)
			(end -0.7874 -0.4064)
			(stroke
				(width 0.1524)
				(type default)
			)
			(layer "F.SilkS")
		)
		(fp_line
			(start -0.12065 -0.305054)
			(end -0.12065 -0.2794)
			(stroke
				(width 0.1)
				(type default)
			)
			(layer "F.Fab")
		)
		(fp_line
			(start -0.67945 -0.305054)
			(end -0.12065 -0.305054)
			(stroke
				(width 0.1)
				(type default)
			)
			(layer "F.Fab")
		)
		(fp_line
			(start 0.67945 -0.3048)
			(end 0.67945 0.3048)
			(stroke
				(width 0.1)
				(type default)
			)
			(layer "F.Fab")
		)
		(fp_line
			(start 0.12065 -0.3048)
			(end 0.67945 -0.3048)
			(stroke
				(width 0.1)
				(type default)
			)
			(layer "F.Fab")
		)
		(fp_line
			(start 0.12065 -0.2794)
			(end 0.12065 -0.3048)
			(stroke
				(width 0.1)
				(type default)
			)
			(layer "F.Fab")
		)
		(fp_line
			(start -0.12065 -0.2794)
			(end 0.12065 -0.2794)
			(stroke
				(width 0.1)
				(type default)
			)
			(layer "F.Fab")
		)
		(fp_line
			(start 0.120396 0.2794)
			(end -0.12065 0.2794)
			(stroke
				(width 0.1)
				(type default)
			)
			(layer "F.Fab")
		)
		(fp_line
			(start -0.12065 0.2794)
			(end -0.12065 0.3048)
			(stroke
				(width 0.1)
				(type default)
			)
			(layer "F.Fab")
		)
		(fp_line
			(start 0.67945 0.3048)
			(end 0.120396 0.3048)
			(stroke
				(width 0.1)
				(type default)
			)
			(layer "F.Fab")
		)
		(fp_line
			(start 0.120396 0.3048)
			(end 0.120396 0.2794)
			(stroke
				(width 0.1)
				(type default)
			)
			(layer "F.Fab")
		)
		(fp_line
			(start -0.12065 0.3048)
			(end -0.67945 0.3048)
			(stroke
				(width 0.1)
				(type default)
			)
			(layer "F.Fab")
		)
		(fp_line
			(start -0.67945 0.3048)
			(end -0.67945 -0.305054)
			(stroke
				(width 0.1)
				(type default)
			)
			(layer "F.Fab")
		)
		(pad "1" smd circle
			(at -0.40005 0 90)
			(size 0 0)
			(layers "F.Cu" "F.Mask" "F.Paste")
			(net "P12V_LED_IMON")
		)
		(pad "2" smd circle
			(at 0.40005 0 90)
			(size 0 0)
			(layers "F.Cu" "F.Mask" "F.Paste")
			(net "GND")
		)
	)
	(footprint ""
		(layer "F.Cu")
		(at 83.947 -17.907 90)
		(property "Reference" "R78"
			(at 0 0 90)
			(layer "F.SilkS")
			(hide yes)
			(effects
				(font
					(size 1.27 1.27)
				)
			)
		)
		(property "Value" ""
			(at 0 0 90)
			(layer "F.Fab")
			(effects
				(font
					(size 1.27 1.27)
				)
			)
		)
		(duplicate_pad_numbers_are_jumpers no)
		(fp_line
			(start 0.7874 -0.4064)
			(end 0.7874 0.4064)
			(stroke
				(width 0.1524)
				(type default)
			)
			(layer "F.SilkS")
		)
		(fp_line
			(start -0.7874 -0.4064)
			(end 0.7874 -0.4064)
			(stroke
				(width 0.1524)
				(type default)
			)
			(layer "F.SilkS")
		)
		(fp_line
			(start 0.7874 0.4064)
			(end -0.7874 0.4064)
			(stroke
				(width 0.1524)
				(type default)
			)
			(layer "F.SilkS")
		)
		(fp_line
			(start -0.7874 0.4064)
			(end -0.7874 -0.4064)
			(stroke
				(width 0.1524)
				(type default)
			)
			(layer "F.SilkS")
		)
		(fp_line
			(start -0.12065 -0.305054)
			(end -0.12065 -0.2794)
			(stroke
				(width 0.1)
				(type default)
			)
			(layer "F.Fab")
		)
		(fp_line
			(start -0.67945 -0.305054)
			(end -0.12065 -0.305054)
			(stroke
				(width 0.1)
				(type default)
			)
			(layer "F.Fab")
		)
		(fp_line
			(start 0.67945 -0.3048)
			(end 0.67945 0.3048)
			(stroke
				(width 0.1)
				(type default)
			)
			(layer "F.Fab")
		)
		(fp_line
			(start 0.12065 -0.3048)
			(end 0.67945 -0.3048)
			(stroke
				(width 0.1)
				(type default)
			)
			(layer "F.Fab")
		)
		(fp_line
			(start 0.12065 -0.2794)
			(end 0.12065 -0.3048)
			(stroke
				(width 0.1)
				(type default)
			)
			(layer "F.Fab")
		)
		(fp_line
			(start -0.12065 -0.2794)
			(end 0.12065 -0.2794)
			(stroke
				(width 0.1)
				(type default)
			)
			(layer "F.Fab")
		)
		(fp_line
			(start 0.120396 0.2794)
			(end -0.12065 0.2794)
			(stroke
				(width 0.1)
				(type default)
			)
			(layer "F.Fab")
		)
		(fp_line
			(start -0.12065 0.2794)
			(end -0.12065 0.3048)
			(stroke
				(width 0.1)
				(type default)
			)
			(layer "F.Fab")
		)
		(fp_line
			(start 0.67945 0.3048)
			(end 0.120396 0.3048)
			(stroke
				(width 0.1)
				(type default)
			)
			(layer "F.Fab")
		)
		(fp_line
			(start 0.120396 0.3048)
			(end 0.120396 0.2794)
			(stroke
				(width 0.1)
				(type default)
			)
			(layer "F.Fab")
		)
		(fp_line
			(start -0.12065 0.3048)
			(end -0.67945 0.3048)
			(stroke
				(width 0.1)
				(type default)
			)
			(layer "F.Fab")
		)
		(fp_line
			(start -0.67945 0.3048)
			(end -0.67945 -0.305054)
			(stroke
				(width 0.1)
				(type default)
			)
			(layer "F.Fab")
		)
		(pad "1" smd circle
			(at -0.40005 0 90)
			(size 0 0)
			(layers "F.Cu" "F.Mask" "F.Paste")
			(net "RST_SMB_FAN_1_R_N")
		)
		(pad "2" smd circle
			(at 0.40005 0 90)
			(size 0 0)
			(layers "F.Cu" "F.Mask" "F.Paste")
			(net "RST_SMB_PDB_BUF_N")
		)
	)
	(footprint ""
		(layer "F.Cu")
		(at 372.160038 -2.035048 -90)
		(property "Reference" "J8"
			(at -9.495282 -10.363962 0)
			(unlocked yes)
			(layer "F.SilkS")
			(effects
				(font
					(size 0.7874 0.5842)
					(thickness 0.1524)
				)
			)
		)
		(property "Value" ""
			(at 0 0 270)
			(layer "F.Fab")
			(effects
				(font
					(size 1.27 1.27)
				)
			)
		)
		(duplicate_pad_numbers_are_jumpers no)
		(fp_line
			(start -8.530082 13.72489)
			(end -8.530082 7.492238)
			(stroke
				(width 0.1524)
				(type default)
			)
			(layer "F.SilkS")
		)
		(fp_line
			(start 1.273048 13.72489)
			(end -8.530082 13.72489)
			(stroke
				(width 0.1524)
				(type default)
			)
			(layer "F.SilkS")
		)
		(fp_line
			(start -5.530088 10.724896)
			(end 1.720088 10.724896)
			(stroke
				(width 0.1524)
				(type default)
			)
			(layer "F.SilkS")
		)
		(fp_line
			(start 1.720088 10.724896)
			(end 1.720088 -8.80491)
			(stroke
				(width 0.1524)
				(type default)
			)
			(layer "F.SilkS")
		)
		(fp_line
			(start -8.530082 -0.915162)
			(end -8.530082 -11.804904)
			(stroke
				(width 0.1524)
				(type default)
			)
			(layer "F.SilkS")
		)
		(fp_line
			(start -5.530088 -8.80491)
			(end -5.530088 10.724896)
			(stroke
				(width 0.1524)
				(type default)
			)
			(layer "F.SilkS")
		)
		(fp_line
			(start 1.720088 -8.80491)
			(end -5.530088 -8.80491)
			(stroke
				(width 0.1524)
				(type default)
			)
			(layer "F.SilkS")
		)
		(fp_line
			(start -8.530082 -11.804904)
			(end 1.654048 -11.804904)
			(stroke
				(width 0.1524)
				(type default)
			)
			(layer "F.SilkS")
		)
		(fp_poly
			(pts
				(xy 1.400048 0.30988) (xy 0.780288 0) (xy 1.400048 -0.30988)
			)
			(stroke
				(width 0)
				(type default)
			)
			(fill yes)
			(layer "F.SilkS")
		)
		(fp_line
			(start -8.530082 13.72489)
			(end -8.530082 -11.804904)
			(stroke
				(width 0.1524)
				(type default)
			)
			(layer "B.SilkS")
		)
		(fp_line
			(start 4.720082 13.72489)
			(end -8.530082 13.72489)
			(stroke
				(width 0.1524)
				(type default)
			)
			(layer "B.SilkS")
		)
		(fp_line
			(start -8.530082 -11.804904)
			(end 4.720082 -11.804904)
			(stroke
				(width 0.1524)
				(type default)
			)
			(layer "B.SilkS")
		)
		(fp_line
			(start 4.720082 -11.804904)
			(end 4.720082 13.72489)
			(stroke
				(width 0.1524)
				(type default)
			)
			(layer "B.SilkS")
		)
		(fp_line
			(start -8.530082 13.72489)
			(end -8.530082 -11.804904)
			(stroke
				(width 0.1)
				(type default)
			)
			(layer "B.Fab")
		)
		(fp_line
			(start 4.720082 13.72489)
			(end -8.530082 13.72489)
			(stroke
				(width 0.1)
				(type default)
			)
			(layer "B.Fab")
		)
		(fp_line
			(start -8.530082 -11.804904)
			(end 4.720082 -11.804904)
			(stroke
				(width 0.1)
				(type default)
			)
			(layer "B.Fab")
		)
		(fp_line
			(start 4.720082 -11.804904)
			(end 4.720082 13.72489)
			(stroke
				(width 0.1)
				(type default)
			)
			(layer "B.Fab")
		)
		(fp_line
			(start -5.530088 10.724896)
			(end 1.720088 10.724896)
			(stroke
				(width 0.1)
				(type default)
			)
			(layer "F.Fab")
		)
		(fp_line
			(start 1.720088 10.724896)
			(end 1.720088 -8.80491)
			(stroke
				(width 0.1)
				(type default)
			)
			(layer "F.Fab")
		)
		(fp_line
			(start -5.530088 -8.80491)
			(end -5.530088 10.724896)
			(stroke
				(width 0.1)
				(type default)
			)
			(layer "F.Fab")
		)
		(fp_line
			(start 1.720088 -8.80491)
			(end -5.530088 -8.80491)
			(stroke
				(width 0.1)
				(type default)
			)
			(layer "F.Fab")
		)
		(fp_poly
			(pts
				(xy 2.939288 0.508) (xy 2.939288 -0.508) (xy 1.923288 0)
			)
			(stroke
				(width 0)
				(type default)
			)
			(fill yes)
			(layer "F.Fab")
		)
		(fp_text user "PRESS-FIT"
			(at -6.918452 -0.203962 0)
			(unlocked yes)
			(layer "F.SilkS")
			(effects
				(font
					(size 1.27 0.9652)
					(thickness 0.1524)
				)
				(justify left)
			)
		)
		(fp_text user "PRESS-FIT"
			(at -5.680202 -6.960362 0)
			(unlocked yes)
			(layer "B.SilkS")
			(effects
				(font
					(size 1.905 1.4224)
					(thickness 0.1524)
				)
				(justify left mirror)
			)
		)
		(fp_text user "PRESS-FIT"
			(at -6.86435 -7.1501 0)
			(unlocked yes)
			(layer "B.Fab")
			(effects
				(font
					(size 1.905 1.4224)
					(thickness 0.1524)
				)
				(justify left mirror)
			)
		)
		(fp_text user "PRESS-FIT"
			(at -6.88975 9.5123 0)
			(unlocked yes)
			(layer "F.Fab")
			(effects
				(font
					(size 1.905 1.4224)
					(thickness 0.1524)
				)
				(justify left)
			)
		)
		(pad "" np_thru_hole circle
			(at -1.905 8.58012 270)
			(size 2.413 2.413)
			(drill 2.413)
			(layers "*.Cu" "*.Mask")
			(clearance 0.381)
			(thermal_gap 0.381)
		)
		(pad "" np_thru_hole circle
			(at -0.55499 -6.65988 270)
			(size 2.413 2.413)
			(drill 2.413)
			(layers "*.Cu" "*.Mask")
			(clearance 0.381)
			(thermal_gap 0.381)
		)
		(pad "P1" thru_hole circle
			(at -0.55499 6.04012 270)
			(size 1.156208 1.156208)
			(drill 0.749808)
			(layers "*.Cu" "*.Mask")
			(remove_unused_layers no)
			(net "P52V_FAN")
			(clearance 0.0508)
			(thermal_gap 0.0508)
		)
		(pad "P2" thru_hole circle
			(at -0.55499 3.50012 270)
			(size 1.156208 1.156208)
			(drill 0.749808)
			(layers "*.Cu" "*.Mask")
			(remove_unused_layers no)
			(net "P52V_FAN")
			(clearance 0.0508)
			(thermal_gap 0.0508)
		)
		(pad "P3" thru_hole circle
			(at -3.25501 3.50012 270)
			(size 1.156208 1.156208)
			(drill 0.749808)
			(layers "*.Cu" "*.Mask")
			(remove_unused_layers no)
			(net "GND")
			(clearance 0.0508)
			(thermal_gap 0.0508)
		)
		(pad "P4" thru_hole circle
			(at -3.25501 6.04012 270)
			(size 1.156208 1.156208)
			(drill 0.749808)
			(layers "*.Cu" "*.Mask")
			(remove_unused_layers no)
			(net "GND")
			(clearance 0.0508)
			(thermal_gap 0.0508)
		)
		(pad "S1" thru_hole rect
			(at 0 0 270)
			(size 1.156208 1.156208)
			(drill 0.749808)
			(layers "*.Cu" "*.Mask")
			(remove_unused_layers no)
			(net "RST_SMB_FAN_0_R_N")
			(clearance 0.0508)
			(thermal_gap 0.0508)
			(padstack
				(mode front_inner_back)
				(layer "Inner"
					(shape circle)
					(size 1.156208 1.156208)
					(clearance 0.0508)
				)
				(layer "B.Cu"
					(shape rect)
					(size 1.156208 1.156208)
					(clearance 0.0508)
				)
			)
		)
		(pad "S2" thru_hole circle
			(at -1.27 -1.27 270)
			(size 1.156208 1.156208)
			(drill 0.749808)
			(layers "*.Cu" "*.Mask")
			(remove_unused_layers no)
			(net "FAN_PWR_EN_0_R")
			(clearance 0.0508)
			(thermal_gap 0.0508)
		)
		(pad "S3" thru_hole circle
			(at 0 -2.54 270)
			(size 1.156208 1.156208)
			(drill 0.749808)
			(layers "*.Cu" "*.Mask")
			(remove_unused_layers no)
			(net "P12V_FAN_LED")
			(clearance 0.0508)
			(thermal_gap 0.0508)
		)
		(pad "S4" thru_hole circle
			(at -1.27 -3.81 270)
			(size 1.156208 1.156208)
			(drill 0.749808)
			(layers "*.Cu" "*.Mask")
			(remove_unused_layers no)
			(net "P3V3_AUX")
			(clearance 0.0508)
			(thermal_gap 0.0508)
		)
		(pad "S5" thru_hole circle
			(at -3.81 -3.81 270)
			(size 1.156208 1.156208)
			(drill 0.749808)
			(layers "*.Cu" "*.Mask")
			(remove_unused_layers no)
			(net "PRSNT_FAN_BP0_R_N")
			(clearance 0.0508)
			(thermal_gap 0.0508)
		)
		(pad "S6" thru_hole circle
			(at -2.54 -2.54 270)
			(size 1.156208 1.156208)
			(drill 0.749808)
			(layers "*.Cu" "*.Mask")
			(remove_unused_layers no)
			(net "GND")
			(clearance 0.0508)
			(thermal_gap 0.0508)
		)
		(pad "S7" thru_hole circle
			(at -3.81 -1.27 270)
			(size 1.156208 1.156208)
			(drill 0.749808)
			(layers "*.Cu" "*.Mask")
			(remove_unused_layers no)
			(net "SMB_PDB_FAN_0_R_SCL")
			(clearance 0.0508)
			(thermal_gap 0.0508)
		)
		(pad "S8" thru_hole circle
			(at -2.54 0 270)
			(size 1.156208 1.156208)
			(drill 0.749808)
			(layers "*.Cu" "*.Mask")
			(remove_unused_layers no)
			(net "SMB_PDB_FAN_0_R_SDA")
			(clearance 0.0508)
			(thermal_gap 0.0508)
		)
		(zone
			(layers "F.Cu" "B.Cu" "In1.Cu" "In2.Cu" "In3.Cu" "In4.Cu" "In5.Cu" "In6.Cu"
				"In7.Cu" "In8.Cu"
			)
			(hatch none 0.5)
			(connect_pads
				(clearance 0)
			)
			(min_thickness 0.25)
			(keepout
				(tracks not_allowed)
				(vias allowed)
				(pads allowed)
				(copperpour not_allowed)
				(footprints allowed)
			)
			(placement
				(enabled no)
				(sheetname "")
			)
			(fill
				(thermal_gap 0.5)
				(thermal_bridge_width 0.5)
				(island_removal_mode 0)
			)
			(polygon
				(pts
					(arc
						(start 365.294418 -3.940048)
						(mid 361.865418 -3.940048)
						(end 365.294418 -3.940048)
					)
				)
			)
		)
		(zone
			(layers "F.Cu" "B.Cu" "In1.Cu" "In2.Cu" "In3.Cu" "In4.Cu" "In5.Cu" "In6.Cu"
				"In7.Cu" "In8.Cu"
			)
			(hatch none 0.5)
			(connect_pads
				(clearance 0)
			)
			(min_thickness 0.25)
			(keepout
				(tracks not_allowed)
				(vias allowed)
				(pads allowed)
				(copperpour not_allowed)
				(footprints allowed)
			)
			(placement
				(enabled no)
				(sheetname "")
			)
			(fill
				(thermal_gap 0.5)
				(thermal_bridge_width 0.5)
				(island_removal_mode 0)
			)
			(polygon
				(pts
					(arc
						(start 380.534672 -2.590038)
						(mid 377.105164 -2.590038)
						(end 380.534672 -2.590038)
					)
				)
			)
		)
		(zone
			(layer "B.Cu")
			(hatch none 0.5)
			(connect_pads
				(clearance 0)
			)
			(min_thickness 0.25)
			(keepout
				(tracks allowed)
				(vias not_allowed)
				(pads allowed)
				(copperpour not_allowed)
				(footprints allowed)
			)
			(placement
				(enabled no)
				(sheetname "")
			)
			(fill
				(thermal_gap 0.5)
				(thermal_bridge_width 0.5)
				(island_removal_mode 0)
			)
			(polygon
				(pts
					(xy 369.301522 -5.931662) (xy 365.478314 -5.931662) (xy 365.478314 -1.948434) (xy 369.301522 -1.948434)
				)
			)
		)
		(zone
			(layer "B.Cu")
			(hatch none 0.5)
			(connect_pads
				(clearance 0)
			)
			(min_thickness 0.25)
			(keepout
				(tracks allowed)
				(vias not_allowed)
				(pads allowed)
				(copperpour not_allowed)
				(footprints allowed)
			)
			(placement
				(enabled no)
				(sheetname "")
			)
			(fill
				(thermal_gap 0.5)
				(thermal_bridge_width 0.5)
				(island_removal_mode 0)
			)
			(polygon
				(pts
					(xy 376.611642 -6.486652) (xy 371.518434 -6.486652) (xy 371.518434 -1.393444) (xy 376.611642 -1.393444)
				)
			)
		)
	)
)
